FILE_TYPE = MACRO_DRAWING;
SET COLOR_WIRE YELLOW;
SET COLOR_PROP MONO;
SET COLOR_DOT WHITE;
SET COLOR_ARC YELLOW;
SET COLOR_BODY GREEN;
SET COLOR_NOTE MONO;
SET PROP_DISPLAY VALUE;
SET PAGE_NUMBER P4;
FORCEADD INTEL_CORP_BPAGE..3
(0 0);
FORCEPROP 2 LAST CUSTOM_TXT_CDS <XR_PAGE_TITLE>
J 0
(-7890 5250);
DISPLAY 0.638298 (-7890 5250);
PAINT PINK (-7890 5250);
DISPLAY INVISIBLE (-7890 5250);
FORCEPROP 1 LAST CUSTOM_TXT_CDS <CON_TC_SNO1>
J 2
(-7150 4525);
PAINT ORANGE (-7150 4525);
FORCEPROP 1 LAST CUSTOM_TXT_CDS <CON_TC_SNO2>
J 2
(-7150 4425);
PAINT ORANGE (-7150 4425);
FORCEPROP 1 LAST CUSTOM_TXT_CDS <CON_TC_SNO3>
J 2
(-7150 4325);
PAINT ORANGE (-7150 4325);
FORCEPROP 1 LAST CUSTOM_TXT_CDS <CON_TC_SNM7>
J 0
(-7050 3925);
PAINT ORANGE (-7050 3925);
FORCEPROP 1 LAST CUSTOM_TXT_CDS <CON_TC_SNM8>
J 0
(-7050 3825);
PAINT ORANGE (-7050 3825);
FORCEPROP 1 LAST CUSTOM_TXT_CDS <CON_TC_SNM9>
J 0
(-7050 3725);
PAINT ORANGE (-7050 3725);
FORCEPROP 1 LAST CUSTOM_TXT_CDS <CURRENT_DESIGN_SHEET> OF <TOTAL_DESIGN_SHEETS>
J 0
(-500 25);
PAINT ORANGE (-500 25);
FORCEPROP 1 LAST CUSTOM_TXT_CDS <CON_LAST_MODIFIED>
J 0
(-1925 350);
PAINT ORANGE (-1925 350);
FORCEPROP 1 LAST CUSTOM_TXT_CDS <CON_TC_SNM1>
J 0
(-7050 4525);
PAINT ORANGE (-7050 4525);
FORCEPROP 1 LAST CUSTOM_TXT_CDS <CON_TC_SNM2>
J 0
(-7050 4425);
PAINT ORANGE (-7050 4425);
FORCEPROP 1 LAST CUSTOM_TXT_CDS <CON_TC_SNM3>
J 0
(-7050 4325);
PAINT ORANGE (-7050 4325);
FORCEPROP 1 LAST CUSTOM_TXT_CDS <CON_TC_SNM4>
J 0
(-7050 4225);
PAINT ORANGE (-7050 4225);
FORCEPROP 1 LAST CUSTOM_TXT_CDS <CON_TC_SNM5>
J 0
(-7050 4125);
PAINT ORANGE (-7050 4125);
FORCEPROP 1 LAST CUSTOM_TXT_CDS <CON_TC_SNM6>
J 0
(-7050 4025);
PAINT ORANGE (-7050 4025);
FORCEPROP 1 LAST CUSTOM_TXT_CDS <CON_TC_SNM10>
J 0
(-7050 3625);
PAINT ORANGE (-7050 3625);
FORCEPROP 1 LAST CUSTOM_TXT_CDS <CON_TC_SNM11>
J 0
(-7050 3525);
PAINT ORANGE (-7050 3525);
FORCEPROP 1 LAST CUSTOM_TXT_CDS <CON_TC_SNM12>
J 0
(-7050 3425);
PAINT ORANGE (-7050 3425);
FORCEPROP 1 LAST CUSTOM_TXT_CDS <CON_TC_SNM13>
J 0
(-7050 3325);
PAINT ORANGE (-7050 3325);
FORCEPROP 1 LAST CUSTOM_TXT_CDS <CON_TC_SNM14>
J 0
(-7050 3225);
PAINT ORANGE (-7050 3225);
FORCEPROP 1 LAST CUSTOM_TXT_CDS <CON_TC_SNM15>
J 0
(-7050 3125);
PAINT ORANGE (-7050 3125);
FORCEPROP 1 LAST CUSTOM_TXT_CDS <CON_TC_SNM16>
J 0
(-7050 3025);
PAINT ORANGE (-7050 3025);
FORCEPROP 1 LAST CUSTOM_TXT_CDS <CON_TC_SNM17>
J 0
(-7050 2925);
PAINT ORANGE (-7050 2925);
FORCEPROP 1 LAST CUSTOM_TXT_CDS <CON_TC_SNM18>
J 0
(-7050 2825);
PAINT ORANGE (-7050 2825);
FORCEPROP 1 LAST CUSTOM_TXT_CDS <CON_TC_SNM19>
J 0
(-7050 2725);
PAINT ORANGE (-7050 2725);
FORCEPROP 1 LAST CUSTOM_TXT_CDS <CON_TC_SNM20>
J 0
(-7050 2625);
PAINT ORANGE (-7050 2625);
FORCEPROP 1 LAST CUSTOM_TXT_CDS <CON_TC_SNM21>
J 0
(-7050 2525);
PAINT ORANGE (-7050 2525);
FORCEPROP 1 LAST CUSTOM_TXT_CDS <CON_TC_SNM22>
J 0
(-7050 2425);
PAINT ORANGE (-7050 2425);
FORCEPROP 1 LAST CUSTOM_TXT_CDS <CON_TC_SNM23>
J 0
(-7050 2325);
PAINT ORANGE (-7050 2325);
FORCEPROP 1 LAST CUSTOM_TXT_CDS <CON_TC_SNM24>
J 0
(-7050 2225);
PAINT ORANGE (-7050 2225);
FORCEPROP 1 LAST CUSTOM_TXT_CDS <CON_TC_SNM25>
J 0
(-7050 2125);
PAINT ORANGE (-7050 2125);
FORCEPROP 1 LAST CUSTOM_TXT_CDS <CON_TC_SNM26>
J 0
(-7050 2025);
PAINT ORANGE (-7050 2025);
FORCEPROP 1 LAST CUSTOM_TXT_CDS <CON_TC_SNM27>
J 0
(-7050 1925);
PAINT ORANGE (-7050 1925);
FORCEPROP 1 LAST CUSTOM_TXT_CDS <CON_TC_SNM28>
J 0
(-7050 1825);
PAINT ORANGE (-7050 1825);
FORCEPROP 1 LAST CUSTOM_TXT_CDS <CON_TC_SNM29>
J 0
(-7050 1725);
PAINT ORANGE (-7050 1725);
FORCEPROP 1 LAST CUSTOM_TXT_CDS <CON_TC_SNM30>
J 0
(-7050 1625);
PAINT ORANGE (-7050 1625);
FORCEPROP 1 LAST CUSTOM_TXT_CDS <CON_TC_SNM31>
J 0
(-7050 1525);
PAINT ORANGE (-7050 1525);
FORCEPROP 1 LAST CUSTOM_TXT_CDS <CON_TC_SNM32>
J 0
(-7050 1425);
PAINT ORANGE (-7050 1425);
FORCEPROP 1 LAST CUSTOM_TXT_CDS <CON_TC_SNM33>
J 0
(-7050 1325);
PAINT ORANGE (-7050 1325);
FORCEPROP 1 LAST CUSTOM_TXT_CDS <CON_TC_SNM34>
J 0
(-7050 1225);
PAINT ORANGE (-7050 1225);
FORCEPROP 1 LAST CUSTOM_TXT_CDS <CON_TC_SNM35>
J 0
(-7050 1125);
PAINT ORANGE (-7050 1125);
FORCEPROP 1 LAST CUSTOM_TXT_CDS <CON_TC_SNM36>
J 0
(-7050 1025);
PAINT ORANGE (-7050 1025);
FORCEPROP 1 LAST CUSTOM_TXT_CDS <CON_TC_SNM37>
J 0
(-7050 925);
PAINT ORANGE (-7050 925);
FORCEPROP 1 LAST CUSTOM_TXT_CDS <CON_TC_SNM38>
J 0
(-7050 825);
PAINT ORANGE (-7050 825);
FORCEPROP 1 LAST CUSTOM_TXT_CDS <CON_TC_SNM39>
J 0
(-7050 725);
PAINT ORANGE (-7050 725);
FORCEPROP 1 LAST CUSTOM_TXT_CDS <CON_TC_SNM40>
J 0
(-7050 625);
PAINT ORANGE (-7050 625);
FORCEPROP 1 LAST CUSTOM_TXT_CDS <CON_TC_SNM41>
J 0
(-4550 4525);
PAINT ORANGE (-4550 4525);
FORCEPROP 1 LAST CUSTOM_TXT_CDS <CON_TC_SNM42>
J 0
(-4550 4425);
PAINT ORANGE (-4550 4425);
FORCEPROP 1 LAST CUSTOM_TXT_CDS <CON_TC_SNM43>
J 0
(-4550 4325);
PAINT ORANGE (-4550 4325);
FORCEPROP 1 LAST CUSTOM_TXT_CDS <CON_TC_SNM44>
J 0
(-4550 4225);
PAINT ORANGE (-4550 4225);
FORCEPROP 1 LAST CUSTOM_TXT_CDS <CON_TC_SNM45>
J 0
(-4550 4125);
PAINT ORANGE (-4550 4125);
FORCEPROP 1 LAST CUSTOM_TXT_CDS <CON_TC_SNM46>
J 0
(-4550 4025);
PAINT ORANGE (-4550 4025);
FORCEPROP 1 LAST CUSTOM_TXT_CDS <CON_TC_SNM47>
J 0
(-4550 3925);
PAINT ORANGE (-4550 3925);
FORCEPROP 1 LAST CUSTOM_TXT_CDS <CON_TC_SNM48>
J 0
(-4550 3825);
PAINT ORANGE (-4550 3825);
FORCEPROP 1 LAST CUSTOM_TXT_CDS <CON_TC_SNM49>
J 0
(-4550 3725);
PAINT ORANGE (-4550 3725);
FORCEPROP 1 LAST CUSTOM_TXT_CDS <CON_TC_SNM50>
J 0
(-4550 3625);
PAINT ORANGE (-4550 3625);
FORCEPROP 1 LAST CUSTOM_TXT_CDS <CON_TC_SNM51>
J 0
(-4550 3525);
PAINT ORANGE (-4550 3525);
FORCEPROP 1 LAST CUSTOM_TXT_CDS <CON_TC_SNM52>
J 0
(-4550 3425);
PAINT ORANGE (-4550 3425);
FORCEPROP 1 LAST CUSTOM_TXT_CDS <CON_TC_SNM53>
J 0
(-4550 3325);
PAINT ORANGE (-4550 3325);
FORCEPROP 1 LAST CUSTOM_TXT_CDS <CON_TC_SNM54>
J 0
(-4550 3225);
PAINT ORANGE (-4550 3225);
FORCEPROP 1 LAST CUSTOM_TXT_CDS <CON_TC_SNM55>
J 0
(-4550 3125);
PAINT ORANGE (-4550 3125);
FORCEPROP 1 LAST CUSTOM_TXT_CDS <CON_TC_SNM56>
J 0
(-4550 3025);
PAINT ORANGE (-4550 3025);
FORCEPROP 1 LAST CUSTOM_TXT_CDS <CON_TC_SNM57>
J 0
(-4550 2925);
PAINT ORANGE (-4550 2925);
FORCEPROP 1 LAST CUSTOM_TXT_CDS <CON_TC_SNM58>
J 0
(-4550 2825);
PAINT ORANGE (-4550 2825);
FORCEPROP 1 LAST CUSTOM_TXT_CDS <CON_TC_SNM59>
J 0
(-4550 2725);
PAINT ORANGE (-4550 2725);
FORCEPROP 1 LAST CUSTOM_TXT_CDS <CON_TC_SNM60>
J 0
(-4550 2625);
PAINT ORANGE (-4550 2625);
FORCEPROP 1 LAST CUSTOM_TXT_CDS <CON_TC_SNM61>
J 0
(-4550 2525);
PAINT ORANGE (-4550 2525);
FORCEPROP 1 LAST CUSTOM_TXT_CDS <CON_TC_SNM62>
J 0
(-4550 2425);
PAINT ORANGE (-4550 2425);
FORCEPROP 1 LAST CUSTOM_TXT_CDS <CON_TC_SNM63>
J 0
(-4550 2325);
PAINT ORANGE (-4550 2325);
FORCEPROP 1 LAST CUSTOM_TXT_CDS <CON_TC_SNM64>
J 0
(-4550 2225);
PAINT ORANGE (-4550 2225);
FORCEPROP 1 LAST CUSTOM_TXT_CDS <CON_TC_SNM65>
J 0
(-4550 2125);
PAINT ORANGE (-4550 2125);
FORCEPROP 1 LAST CUSTOM_TXT_CDS <CON_TC_SNM66>
J 0
(-4550 2025);
PAINT ORANGE (-4550 2025);
FORCEPROP 1 LAST CUSTOM_TXT_CDS <CON_TC_SNM67>
J 0
(-4550 1925);
PAINT ORANGE (-4550 1925);
FORCEPROP 1 LAST CUSTOM_TXT_CDS <CON_TC_SNM68>
J 0
(-4550 1825);
PAINT ORANGE (-4550 1825);
FORCEPROP 1 LAST CUSTOM_TXT_CDS <CON_TC_SNM69>
J 0
(-4550 1725);
PAINT ORANGE (-4550 1725);
FORCEPROP 1 LAST CUSTOM_TXT_CDS <CON_TC_SNM70>
J 0
(-4550 1625);
PAINT ORANGE (-4550 1625);
FORCEPROP 1 LAST CUSTOM_TXT_CDS <CON_TC_SNM71>
J 0
(-4550 1525);
PAINT ORANGE (-4550 1525);
FORCEPROP 1 LAST CUSTOM_TXT_CDS <CON_TC_SNM72>
J 0
(-4550 1425);
PAINT ORANGE (-4550 1425);
FORCEPROP 1 LAST CUSTOM_TXT_CDS <CON_TC_SNM73>
J 0
(-4550 1325);
PAINT ORANGE (-4550 1325);
FORCEPROP 1 LAST CUSTOM_TXT_CDS <CON_TC_SNM74>
J 0
(-4550 1225);
PAINT ORANGE (-4550 1225);
FORCEPROP 1 LAST CUSTOM_TXT_CDS <CON_TC_SNM75>
J 0
(-4550 1125);
PAINT ORANGE (-4550 1125);
FORCEPROP 1 LAST CUSTOM_TXT_CDS <CON_TC_SNM76>
J 0
(-4550 1025);
PAINT ORANGE (-4550 1025);
FORCEPROP 1 LAST CUSTOM_TXT_CDS <CON_TC_SNM77>
J 0
(-4550 925);
PAINT ORANGE (-4550 925);
FORCEPROP 1 LAST CUSTOM_TXT_CDS <CON_TC_SNM78>
J 0
(-4550 825);
PAINT ORANGE (-4550 825);
FORCEPROP 1 LAST CUSTOM_TXT_CDS <CON_TC_SNM79>
J 0
(-4550 725);
PAINT ORANGE (-4550 725);
FORCEPROP 1 LAST CUSTOM_TXT_CDS <CON_TC_SNM80>
J 0
(-4550 625);
PAINT ORANGE (-4550 625);
FORCEPROP 1 LAST CUSTOM_TXT_CDS <CON_TC_SNM81>
J 0
(-2050 4525);
PAINT ORANGE (-2050 4525);
FORCEPROP 1 LAST CUSTOM_TXT_CDS <CON_TC_SNM82>
J 0
(-2050 4425);
PAINT ORANGE (-2050 4425);
FORCEPROP 1 LAST CUSTOM_TXT_CDS <CON_TC_SNM83>
J 0
(-2050 4325);
PAINT ORANGE (-2050 4325);
FORCEPROP 1 LAST CUSTOM_TXT_CDS <CON_TC_SNM84>
J 0
(-2050 4225);
PAINT ORANGE (-2050 4225);
FORCEPROP 1 LAST CUSTOM_TXT_CDS <CON_TC_SNM85>
J 0
(-2050 4125);
PAINT ORANGE (-2050 4125);
FORCEPROP 1 LAST CUSTOM_TXT_CDS <CON_TC_SNM86>
J 0
(-2050 4025);
PAINT ORANGE (-2050 4025);
FORCEPROP 1 LAST CUSTOM_TXT_CDS <CON_TC_SNM87>
J 0
(-2050 3925);
PAINT ORANGE (-2050 3925);
FORCEPROP 1 LAST CUSTOM_TXT_CDS <CON_TC_SNM88>
J 0
(-2050 3825);
PAINT ORANGE (-2050 3825);
FORCEPROP 1 LAST CUSTOM_TXT_CDS <CON_TC_SNM89>
J 0
(-2050 3725);
PAINT ORANGE (-2050 3725);
FORCEPROP 1 LAST CUSTOM_TXT_CDS <CON_TC_SNM90>
J 0
(-2050 3625);
PAINT ORANGE (-2050 3625);
FORCEPROP 1 LAST CUSTOM_TXT_CDS <CON_TC_SNM91>
J 0
(-2050 3525);
PAINT ORANGE (-2050 3525);
FORCEPROP 1 LAST CUSTOM_TXT_CDS <CON_TC_SNM92>
J 0
(-2050 3425);
PAINT ORANGE (-2050 3425);
FORCEPROP 1 LAST CUSTOM_TXT_CDS <CON_TC_SNM93>
J 0
(-2050 3325);
PAINT ORANGE (-2050 3325);
FORCEPROP 1 LAST CUSTOM_TXT_CDS <CON_TC_SNM94>
J 0
(-2050 3225);
PAINT ORANGE (-2050 3225);
FORCEPROP 1 LAST CUSTOM_TXT_CDS <CON_TC_SNM95>
J 0
(-2050 3125);
PAINT ORANGE (-2050 3125);
FORCEPROP 1 LAST CUSTOM_TXT_CDS <CON_TC_SNM96>
J 0
(-2050 3025);
PAINT ORANGE (-2050 3025);
FORCEPROP 1 LAST CUSTOM_TXT_CDS <CON_TC_SNM97>
J 0
(-2050 2925);
PAINT ORANGE (-2050 2925);
FORCEPROP 1 LAST CUSTOM_TXT_CDS <CON_TC_SNM98>
J 0
(-2050 2825);
PAINT ORANGE (-2050 2825);
FORCEPROP 1 LAST CUSTOM_TXT_CDS <CON_TC_SNM99>
J 0
(-2050 2725);
PAINT ORANGE (-2050 2725);
FORCEPROP 1 LAST CUSTOM_TXT_CDS <CON_TC_SNM100>
J 0
(-2050 2625);
PAINT ORANGE (-2050 2625);
FORCEPROP 1 LAST CUSTOM_TXT_CDS <CON_TC_SNM101>
J 0
(-2050 2525);
PAINT ORANGE (-2050 2525);
FORCEPROP 1 LAST CUSTOM_TXT_CDS <CON_TC_SNM102>
J 0
(-2050 2425);
PAINT ORANGE (-2050 2425);
FORCEPROP 1 LAST CUSTOM_TXT_CDS <CON_TC_SNM103>
J 0
(-2050 2325);
PAINT ORANGE (-2050 2325);
FORCEPROP 1 LAST CUSTOM_TXT_CDS <CON_TC_SNM104>
J 0
(-2050 2225);
PAINT ORANGE (-2050 2225);
FORCEPROP 1 LAST CUSTOM_TXT_CDS <CON_TC_SNM105>
J 0
(-2050 2125);
PAINT ORANGE (-2050 2125);
FORCEPROP 1 LAST CUSTOM_TXT_CDS <CON_TC_SNM106>
J 0
(-2050 2025);
PAINT ORANGE (-2050 2025);
FORCEPROP 1 LAST CUSTOM_TXT_CDS <CON_TC_SNM107>
J 0
(-2050 1925);
PAINT ORANGE (-2050 1925);
FORCEPROP 1 LAST CUSTOM_TXT_CDS <CON_TC_SNM108>
J 0
(-2050 1825);
PAINT ORANGE (-2050 1825);
FORCEPROP 1 LAST CUSTOM_TXT_CDS <CON_TC_SNM109>
J 0
(-2050 1725);
PAINT ORANGE (-2050 1725);
FORCEPROP 1 LAST CUSTOM_TXT_CDS <CON_TC_SNM110>
J 0
(-2050 1625);
PAINT ORANGE (-2050 1625);
FORCEPROP 1 LAST CUSTOM_TXT_CDS <CON_TC_SNM111>
J 0
(-2050 1525);
PAINT ORANGE (-2050 1525);
FORCEPROP 1 LAST CUSTOM_TXT_CDS <CON_TC_SNM112>
J 0
(-2050 1425);
PAINT ORANGE (-2050 1425);
FORCEPROP 1 LAST CUSTOM_TXT_CDS <CON_TC_SNM113>
J 0
(-2050 1325);
PAINT ORANGE (-2050 1325);
FORCEPROP 1 LAST CUSTOM_TXT_CDS <CON_TC_SNM114>
J 0
(-2050 1225);
PAINT ORANGE (-2050 1225);
FORCEPROP 1 LAST CUSTOM_TXT_CDS <CON_TC_SNM115>
J 0
(-2050 1125);
PAINT ORANGE (-2050 1125);
FORCEPROP 1 LAST CUSTOM_TXT_CDS <CON_TC_SNM116>
J 0
(-2050 1025);
PAINT ORANGE (-2050 1025);
FORCEPROP 1 LAST CUSTOM_TXT_CDS <CON_TC_SNM117>
J 0
(-2050 925);
PAINT ORANGE (-2050 925);
FORCEPROP 1 LAST CUSTOM_TXT_CDS <CON_TC_SNM118>
J 0
(-2050 825);
PAINT ORANGE (-2050 825);
FORCEPROP 1 LAST CUSTOM_TXT_CDS <CON_TC_SNM119>
J 0
(-2050 725);
PAINT ORANGE (-2050 725);
FORCEPROP 1 LAST CUSTOM_TXT_CDS <CON_TC_SNM120>
J 0
(-2050 625);
PAINT ORANGE (-2050 625);
FORCEPROP 1 LAST CUSTOM_TXT_CDS <CON_TC_SNO4>
J 2
(-7150 4225);
PAINT ORANGE (-7150 4225);
FORCEPROP 1 LAST CUSTOM_TXT_CDS <CON_TC_SNO5>
J 2
(-7150 4125);
PAINT ORANGE (-7150 4125);
FORCEPROP 1 LAST CUSTOM_TXT_CDS <CON_TC_SNO6>
J 2
(-7150 4025);
PAINT ORANGE (-7150 4025);
FORCEPROP 1 LAST CUSTOM_TXT_CDS <CON_TC_SNO7>
J 2
(-7150 3925);
PAINT ORANGE (-7150 3925);
FORCEPROP 1 LAST CUSTOM_TXT_CDS <CON_TC_SNO8>
J 2
(-7150 3825);
PAINT ORANGE (-7150 3825);
FORCEPROP 1 LAST CUSTOM_TXT_CDS <CON_TC_SNO9>
J 2
(-7150 3725);
PAINT ORANGE (-7150 3725);
FORCEPROP 1 LAST CUSTOM_TXT_CDS <CON_TC_SNO10>
J 2
(-7150 3625);
PAINT ORANGE (-7150 3625);
FORCEPROP 1 LAST CUSTOM_TXT_CDS <CON_TC_SNO11>
J 2
(-7150 3525);
PAINT ORANGE (-7150 3525);
FORCEPROP 1 LAST CUSTOM_TXT_CDS <CON_TC_SNO12>
J 2
(-7150 3425);
PAINT ORANGE (-7150 3425);
FORCEPROP 1 LAST CUSTOM_TXT_CDS <CON_TC_SNO13>
J 2
(-7150 3325);
PAINT ORANGE (-7150 3325);
FORCEPROP 1 LAST CUSTOM_TXT_CDS <CON_TC_SNO14>
J 2
(-7150 3225);
PAINT ORANGE (-7150 3225);
FORCEPROP 1 LAST CUSTOM_TXT_CDS <CON_TC_SNO15>
J 2
(-7150 3125);
PAINT ORANGE (-7150 3125);
FORCEPROP 1 LAST CUSTOM_TXT_CDS <CON_TC_SNO16>
J 2
(-7150 3025);
PAINT ORANGE (-7150 3025);
FORCEPROP 1 LAST CUSTOM_TXT_CDS <CON_TC_SNO17>
J 2
(-7150 2925);
PAINT ORANGE (-7150 2925);
FORCEPROP 1 LAST CUSTOM_TXT_CDS <CON_TC_SNO18>
J 2
(-7150 2825);
PAINT ORANGE (-7150 2825);
FORCEPROP 1 LAST CUSTOM_TXT_CDS <CON_TC_SNO19>
J 2
(-7150 2725);
PAINT ORANGE (-7150 2725);
FORCEPROP 1 LAST CUSTOM_TXT_CDS <CON_TC_SNO20>
J 2
(-7150 2625);
PAINT ORANGE (-7150 2625);
FORCEPROP 1 LAST CUSTOM_TXT_CDS <CON_TC_SNO21>
J 2
(-7150 2525);
PAINT ORANGE (-7150 2525);
FORCEPROP 1 LAST CUSTOM_TXT_CDS <CON_TC_SNO22>
J 2
(-7150 2425);
PAINT ORANGE (-7150 2425);
FORCEPROP 1 LAST CUSTOM_TXT_CDS <CON_TC_SNO23>
J 2
(-7150 2325);
PAINT ORANGE (-7150 2325);
FORCEPROP 1 LAST CUSTOM_TXT_CDS <CON_TC_SNO24>
J 2
(-7150 2225);
PAINT ORANGE (-7150 2225);
FORCEPROP 1 LAST CUSTOM_TXT_CDS <CON_TC_SNO25>
J 2
(-7150 2125);
PAINT ORANGE (-7150 2125);
FORCEPROP 1 LAST CUSTOM_TXT_CDS <CON_TC_SNO26>
J 2
(-7150 2025);
PAINT ORANGE (-7150 2025);
FORCEPROP 1 LAST CUSTOM_TXT_CDS <CON_TC_SNO27>
J 2
(-7150 1925);
PAINT ORANGE (-7150 1925);
FORCEPROP 1 LAST CUSTOM_TXT_CDS <CON_TC_SNO28>
J 2
(-7150 1825);
PAINT ORANGE (-7150 1825);
FORCEPROP 1 LAST CUSTOM_TXT_CDS <CON_TC_SNO29>
J 2
(-7150 1725);
PAINT ORANGE (-7150 1725);
FORCEPROP 1 LAST CUSTOM_TXT_CDS <CON_TC_SNO30>
J 2
(-7150 1625);
PAINT ORANGE (-7150 1625);
FORCEPROP 1 LAST CUSTOM_TXT_CDS <CON_TC_SNO31>
J 2
(-7150 1525);
PAINT ORANGE (-7150 1525);
FORCEPROP 1 LAST CUSTOM_TXT_CDS <CON_TC_SNO32>
J 2
(-7150 1425);
PAINT ORANGE (-7150 1425);
FORCEPROP 1 LAST CUSTOM_TXT_CDS <CON_TC_SNO33>
J 2
(-7150 1325);
PAINT ORANGE (-7150 1325);
FORCEPROP 1 LAST CUSTOM_TXT_CDS <CON_TC_SNO34>
J 2
(-7150 1225);
PAINT ORANGE (-7150 1225);
FORCEPROP 1 LAST CUSTOM_TXT_CDS <CON_TC_SNO35>
J 2
(-7150 1125);
PAINT ORANGE (-7150 1125);
FORCEPROP 1 LAST CUSTOM_TXT_CDS <CON_TC_SNO36>
J 2
(-7150 1025);
PAINT ORANGE (-7150 1025);
FORCEPROP 1 LAST CUSTOM_TXT_CDS <CON_TC_SNO37>
J 2
(-7150 925);
PAINT ORANGE (-7150 925);
FORCEPROP 1 LAST CUSTOM_TXT_CDS <CON_TC_SNO38>
J 2
(-7150 825);
PAINT ORANGE (-7150 825);
FORCEPROP 1 LAST CUSTOM_TXT_CDS <CON_TC_SNO39>
J 2
(-7150 725);
PAINT ORANGE (-7150 725);
FORCEPROP 1 LAST CUSTOM_TXT_CDS <CON_TC_SNO40>
J 2
(-7150 625);
PAINT ORANGE (-7150 625);
FORCEPROP 1 LAST CUSTOM_TXT_CDS <CON_TC_SNO41>
J 2
(-4650 4525);
PAINT ORANGE (-4650 4525);
FORCEPROP 1 LAST CUSTOM_TXT_CDS <CON_TC_SNO42>
J 2
(-4650 4425);
PAINT ORANGE (-4650 4425);
FORCEPROP 1 LAST CUSTOM_TXT_CDS <CON_TC_SNO43>
J 2
(-4650 4325);
PAINT ORANGE (-4650 4325);
FORCEPROP 1 LAST CUSTOM_TXT_CDS <CON_TC_SNO44>
J 2
(-4650 4225);
PAINT ORANGE (-4650 4225);
FORCEPROP 1 LAST CUSTOM_TXT_CDS <CON_TC_SNO45>
J 2
(-4650 4125);
PAINT ORANGE (-4650 4125);
FORCEPROP 1 LAST CUSTOM_TXT_CDS <CON_TC_SNO46>
J 2
(-4650 4025);
PAINT ORANGE (-4650 4025);
FORCEPROP 1 LAST CUSTOM_TXT_CDS <CON_TC_SNO47>
J 2
(-4650 3925);
PAINT ORANGE (-4650 3925);
FORCEPROP 1 LAST CUSTOM_TXT_CDS <CON_TC_SNO48>
J 2
(-4650 3825);
PAINT ORANGE (-4650 3825);
FORCEPROP 1 LAST CUSTOM_TXT_CDS <CON_TC_SNO49>
J 2
(-4650 3725);
PAINT ORANGE (-4650 3725);
FORCEPROP 1 LAST CUSTOM_TXT_CDS <CON_TC_SNO50>
J 2
(-4650 3625);
PAINT ORANGE (-4650 3625);
FORCEPROP 1 LAST CUSTOM_TXT_CDS <CON_TC_SNO51>
J 2
(-4650 3525);
PAINT ORANGE (-4650 3525);
FORCEPROP 1 LAST CUSTOM_TXT_CDS <CON_TC_SNO52>
J 2
(-4650 3425);
PAINT ORANGE (-4650 3425);
FORCEPROP 1 LAST CUSTOM_TXT_CDS <CON_TC_SNO53>
J 2
(-4650 3325);
PAINT ORANGE (-4650 3325);
FORCEPROP 1 LAST CUSTOM_TXT_CDS <CON_TC_SNO54>
J 2
(-4650 3225);
PAINT ORANGE (-4650 3225);
FORCEPROP 1 LAST CUSTOM_TXT_CDS <CON_TC_SNO55>
J 2
(-4650 3125);
PAINT ORANGE (-4650 3125);
FORCEPROP 1 LAST CUSTOM_TXT_CDS <CON_TC_SNO56>
J 2
(-4650 3025);
PAINT ORANGE (-4650 3025);
FORCEPROP 1 LAST CUSTOM_TXT_CDS <CON_TC_SNO57>
J 2
(-4650 2925);
PAINT ORANGE (-4650 2925);
FORCEPROP 1 LAST CUSTOM_TXT_CDS <CON_TC_SNO58>
J 2
(-4650 2825);
PAINT ORANGE (-4650 2825);
FORCEPROP 1 LAST CUSTOM_TXT_CDS <CON_TC_SNO59>
J 2
(-4650 2725);
PAINT ORANGE (-4650 2725);
FORCEPROP 1 LAST CUSTOM_TXT_CDS <CON_TC_SNO60>
J 2
(-4650 2625);
PAINT ORANGE (-4650 2625);
FORCEPROP 1 LAST CUSTOM_TXT_CDS <CON_TC_SNO61>
J 2
(-4650 2525);
PAINT ORANGE (-4650 2525);
FORCEPROP 1 LAST CUSTOM_TXT_CDS <CON_TC_SNO62>
J 2
(-4650 2425);
PAINT ORANGE (-4650 2425);
FORCEPROP 1 LAST CUSTOM_TXT_CDS <CON_TC_SNO63>
J 2
(-4650 2325);
PAINT ORANGE (-4650 2325);
FORCEPROP 1 LAST CUSTOM_TXT_CDS <CON_TC_SNO64>
J 2
(-4650 2225);
PAINT ORANGE (-4650 2225);
FORCEPROP 1 LAST CUSTOM_TXT_CDS <CON_TC_SNO65>
J 2
(-4650 2125);
PAINT ORANGE (-4650 2125);
FORCEPROP 1 LAST CUSTOM_TXT_CDS <CON_TC_SNO66>
J 2
(-4650 2025);
PAINT ORANGE (-4650 2025);
FORCEPROP 1 LAST CUSTOM_TXT_CDS <CON_TC_SNO67>
J 2
(-4650 1925);
PAINT ORANGE (-4650 1925);
FORCEPROP 1 LAST CUSTOM_TXT_CDS <CON_TC_SNO68>
J 2
(-4650 1825);
PAINT ORANGE (-4650 1825);
FORCEPROP 1 LAST CUSTOM_TXT_CDS <CON_TC_SNO69>
J 2
(-4650 1725);
PAINT ORANGE (-4650 1725);
FORCEPROP 1 LAST CUSTOM_TXT_CDS <CON_TC_SNO70>
J 2
(-4650 1625);
PAINT ORANGE (-4650 1625);
FORCEPROP 1 LAST CUSTOM_TXT_CDS <CON_TC_SNO71>
J 2
(-4650 1525);
PAINT ORANGE (-4650 1525);
FORCEPROP 1 LAST CUSTOM_TXT_CDS <CON_TC_SNO72>
J 2
(-4650 1425);
PAINT ORANGE (-4650 1425);
FORCEPROP 1 LAST CUSTOM_TXT_CDS <CON_TC_SNO73>
J 2
(-4650 1325);
PAINT ORANGE (-4650 1325);
FORCEPROP 1 LAST CUSTOM_TXT_CDS <CON_TC_SNO74>
J 2
(-4650 1225);
PAINT ORANGE (-4650 1225);
FORCEPROP 1 LAST CUSTOM_TXT_CDS <CON_TC_SNO75>
J 2
(-4650 1125);
PAINT ORANGE (-4650 1125);
FORCEPROP 1 LAST CUSTOM_TXT_CDS <CON_TC_SNO76>
J 2
(-4650 1025);
PAINT ORANGE (-4650 1025);
FORCEPROP 1 LAST CUSTOM_TXT_CDS <CON_TC_SNO77>
J 2
(-4650 925);
PAINT ORANGE (-4650 925);
FORCEPROP 1 LAST CUSTOM_TXT_CDS <CON_TC_SNO78>
J 2
(-4650 825);
PAINT ORANGE (-4650 825);
FORCEPROP 1 LAST CUSTOM_TXT_CDS <CON_TC_SNO79>
J 2
(-4650 725);
PAINT ORANGE (-4650 725);
FORCEPROP 1 LAST CUSTOM_TXT_CDS <CON_TC_SNO80>
J 2
(-4650 625);
PAINT ORANGE (-4650 625);
FORCEPROP 1 LAST CUSTOM_TXT_CDS <CON_TC_SNO81>
J 2
(-2150 4525);
PAINT ORANGE (-2150 4525);
FORCEPROP 1 LAST CUSTOM_TXT_CDS <CON_TC_SNO82>
J 2
(-2150 4425);
PAINT ORANGE (-2150 4425);
FORCEPROP 1 LAST CUSTOM_TXT_CDS <CON_TC_SNO83>
J 2
(-2150 4325);
PAINT ORANGE (-2150 4325);
FORCEPROP 1 LAST CUSTOM_TXT_CDS <CON_TC_SNO84>
J 2
(-2150 4225);
PAINT ORANGE (-2150 4225);
FORCEPROP 1 LAST CUSTOM_TXT_CDS <CON_TC_SNO85>
J 2
(-2150 4125);
PAINT ORANGE (-2150 4125);
FORCEPROP 1 LAST CUSTOM_TXT_CDS <CON_TC_SNO86>
J 2
(-2150 4025);
PAINT ORANGE (-2150 4025);
FORCEPROP 1 LAST CUSTOM_TXT_CDS <CON_TC_SNO87>
J 2
(-2150 3925);
PAINT ORANGE (-2150 3925);
FORCEPROP 1 LAST CUSTOM_TXT_CDS <CON_TC_SNO88>
J 2
(-2150 3825);
PAINT ORANGE (-2150 3825);
FORCEPROP 1 LAST CUSTOM_TXT_CDS <CON_TC_SNO89>
J 2
(-2150 3725);
PAINT ORANGE (-2150 3725);
FORCEPROP 1 LAST CUSTOM_TXT_CDS <CON_TC_SNO90>
J 2
(-2150 3625);
PAINT ORANGE (-2150 3625);
FORCEPROP 1 LAST CUSTOM_TXT_CDS <CON_TC_SNO91>
J 2
(-2150 3525);
PAINT ORANGE (-2150 3525);
FORCEPROP 1 LAST CUSTOM_TXT_CDS <CON_TC_SNO92>
J 2
(-2150 3425);
PAINT ORANGE (-2150 3425);
FORCEPROP 1 LAST CUSTOM_TXT_CDS <CON_TC_SNO93>
J 2
(-2150 3325);
PAINT ORANGE (-2150 3325);
FORCEPROP 1 LAST CUSTOM_TXT_CDS <CON_TC_SNO94>
J 2
(-2150 3225);
PAINT ORANGE (-2150 3225);
FORCEPROP 1 LAST CUSTOM_TXT_CDS <CON_TC_SNO95>
J 2
(-2150 3125);
PAINT ORANGE (-2150 3125);
FORCEPROP 1 LAST CUSTOM_TXT_CDS <CON_TC_SNO96>
J 2
(-2150 3025);
PAINT ORANGE (-2150 3025);
FORCEPROP 1 LAST CUSTOM_TXT_CDS <CON_TC_SNO97>
J 2
(-2150 2925);
PAINT ORANGE (-2150 2925);
FORCEPROP 1 LAST CUSTOM_TXT_CDS <CON_TC_SNO98>
J 2
(-2150 2825);
PAINT ORANGE (-2150 2825);
FORCEPROP 1 LAST CUSTOM_TXT_CDS <CON_TC_SNO99>
J 2
(-2150 2725);
PAINT ORANGE (-2150 2725);
FORCEPROP 1 LAST CUSTOM_TXT_CDS <CON_TC_SNO100>
J 2
(-2150 2625);
PAINT ORANGE (-2150 2625);
FORCEPROP 1 LAST CUSTOM_TXT_CDS <CON_TC_SNO101>
J 2
(-2150 2525);
PAINT ORANGE (-2150 2525);
FORCEPROP 1 LAST CUSTOM_TXT_CDS <CON_TC_SNO102>
J 2
(-2150 2425);
PAINT ORANGE (-2150 2425);
FORCEPROP 1 LAST CUSTOM_TXT_CDS <CON_TC_SNO103>
J 2
(-2150 2325);
PAINT ORANGE (-2150 2325);
FORCEPROP 1 LAST CUSTOM_TXT_CDS <CON_TC_SNO104>
J 2
(-2150 2225);
PAINT ORANGE (-2150 2225);
FORCEPROP 1 LAST CUSTOM_TXT_CDS <CON_TC_SNO105>
J 2
(-2150 2125);
PAINT ORANGE (-2150 2125);
FORCEPROP 1 LAST CUSTOM_TXT_CDS <CON_TC_SNO106>
J 2
(-2150 2025);
PAINT ORANGE (-2150 2025);
FORCEPROP 1 LAST CUSTOM_TXT_CDS <CON_TC_SNO107>
J 2
(-2150 1925);
PAINT ORANGE (-2150 1925);
FORCEPROP 1 LAST CUSTOM_TXT_CDS <CON_TC_SNO108>
J 2
(-2150 1825);
PAINT ORANGE (-2150 1825);
FORCEPROP 1 LAST CUSTOM_TXT_CDS <CON_TC_SNO109>
J 2
(-2150 1725);
PAINT ORANGE (-2150 1725);
FORCEPROP 1 LAST CUSTOM_TXT_CDS <CON_TC_SNO110>
J 2
(-2150 1625);
PAINT ORANGE (-2150 1625);
FORCEPROP 1 LAST CUSTOM_TXT_CDS <CON_TC_SNO111>
J 2
(-2150 1525);
PAINT ORANGE (-2150 1525);
FORCEPROP 1 LAST CUSTOM_TXT_CDS <CON_TC_SNO112>
J 2
(-2150 1425);
PAINT ORANGE (-2150 1425);
FORCEPROP 1 LAST CUSTOM_TXT_CDS <CON_TC_SNO113>
J 2
(-2150 1325);
PAINT ORANGE (-2150 1325);
FORCEPROP 1 LAST CUSTOM_TXT_CDS <CON_TC_SNO114>
J 2
(-2150 1225);
PAINT ORANGE (-2150 1225);
FORCEPROP 1 LAST CUSTOM_TXT_CDS <CON_TC_SNO115>
J 2
(-2150 1125);
PAINT ORANGE (-2150 1125);
FORCEPROP 1 LAST CUSTOM_TXT_CDS <CON_TC_SNO116>
J 2
(-2150 1025);
PAINT ORANGE (-2150 1025);
FORCEPROP 1 LAST CUSTOM_TXT_CDS <CON_TC_SNO117>
J 2
(-2150 925);
PAINT ORANGE (-2150 925);
FORCEPROP 1 LAST CUSTOM_TXT_CDS <CON_TC_SNO118>
J 2
(-2150 825);
PAINT ORANGE (-2150 825);
FORCEPROP 1 LAST CUSTOM_TXT_CDS <CON_TC_SNO119>
J 2
(-2150 725);
PAINT ORANGE (-2150 725);
FORCEPROP 1 LAST CUSTOM_TXT_CDS <CON_TC_SNO120>
J 2
(-2150 625);
PAINT ORANGE (-2150 625);
FORCEPROP 1 LAST SCH_ADDRESS3 Santa Clara, CA 95052-8119
J 0
(-3975 25);
DISPLAY 0.617021 (-3975 25);
PAINT GREEN (-3975 25);
FORCEPROP 1 LAST SCH_ADDRESS2 P.O. BOX 58119
J 0
(-3975 75);
DISPLAY 0.617021 (-3975 75);
PAINT GREEN (-3975 75);
FORCEPROP 1 LAST SCH_ADDRESS1 2200 Mission College Blvd.
J 0
(-3975 125);
DISPLAY 0.617021 (-3975 125);
PAINT GREEN (-3975 125);
FORCEPROP 1 LAST SCH_TITLE INDEX (3 OF 3)
J 0
(-7950 50);
DISPLAY 1.212766 (-7950 50);
PAINT ORANGE (-7950 50);
FORCEPROP 1 LAST SCH_NUMBER H4694802
J 0
(-1300 150);
DISPLAY 1.212766 (-1300 150);
PAINT YELLOW (-1300 150);
FORCEPROP 1 LAST SCH_DEPT BESD
J 1
(-4450 100);
DISPLAY 1.212766 (-4450 100);
PAINT YELLOW (-4450 100);
FORCEPROP 1 LAST SCH_REV 2.420
J 0
(-250 150);
DISPLAY 0.978723 (-250 150);
PAINT YELLOW (-250 150);
FORCEPROP 2 LAST PAGE_BORDER TRUE
J 0
(-7890 5250);
DISPLAY 0.851064 (-7890 5250);
PAINT PINK (-7890 5250);
DISPLAY INVISIBLE (-7890 5250);
FORCEPROP 2 LAST CDS_LIB mstr_symbols
J 0
(0 0);
PAINT ORANGE (0 0);
DISPLAY INVISIBLE (0 0);
FORCEPROP 1 LAST TOC_SYMBOL TRUE
J 0
(-7950 5050);
PAINT ORANGE (-7950 5050);
DISPLAY INVISIBLE (-7950 5050);
FORCEPROP 1 LAST COMMENT_BODY TRUE
J 0
(12 12);
DISPLAY 0.468085 (12 12);
PAINT GREEN (12 12);
DISPLAY INVISIBLE (12 12);
FORCEPROP 1 LAST CDS_CON_LAST_MODIFIED Tue Dec 01 11:47:55 2015
J 0
(-1425 325);
PAINT ORANGE (-1425 325);
DISPLAY INVISIBLE (-1425 325);
FORCEPROP 2 LAST CDS_XR_PAGE_TITLE CR-4 : @BASEBOARD_FAB2_LIB.BASEBOARD_FAB2(SCH_1):PAGE4
J 0
(-7890 5250);
DISPLAY 0.638298 (-7890 5250);
PAINT PINK (-7890 5250);
DISPLAY INVISIBLE (-7890 5250);
QUIT
